(kicad_pcb
	(version 20240108)
	(generator "pcbnew")
	(generator_version "8.0")
	(general
		(thickness 1.62)
		(legacy_teardrops no)
	)
	(paper "A4")
	(title_block
		(title "Jetson Orin Baseboard")
		(date "2025-03-12")
		(rev "1.3.4")
		(company "Antmicro Ltd")
		(comment 1 "www.antmicro.com")
		(comment 9 "footprints 10-14 of 677")
	)
	(layers
		(0 "F.Cu" signal)
		(1 "In1.Cu" signal)
		(2 "In2.Cu" signal)
		(3 "In3.Cu" signal)
		(4 "In4.Cu" jumper)
		(5 "In5.Cu" signal)
		(6 "In6.Cu" signal)
		(31 "B.Cu" signal)
		(32 "B.Adhes" user "B.Adhesive")
		(33 "F.Adhes" user "F.Adhesive")
		(34 "B.Paste" user)
		(35 "F.Paste" user)
		(36 "B.SilkS" user "B.Silkscreen")
		(37 "F.SilkS" user "F.Silkscreen")
		(38 "B.Mask" user)
		(39 "F.Mask" user)
		(40 "Dwgs.User" user "User.Drawings")
		(41 "Cmts.User" user "User.Comments")
		(42 "Eco1.User" user "User.Eco1")
		(43 "Eco2.User" user "User.Eco2")
		(44 "Edge.Cuts" user)
		(45 "Margin" user)
		(46 "B.CrtYd" user "B.Courtyard")
		(47 "F.CrtYd" user "F.Courtyard")
		(48 "B.Fab" user)
		(49 "F.Fab" user)
	)
	(footprint "antmicro-footprints:USON-10_2.5x1mm_P0.5mm"
		(layer "F.Cu")
		(at 70 111.367469 90)
		(descr "USON-10 2.5x1mm_ Pitch 0.5mm")
		(tags "USON-10 2.5x1mm Pitch 0.5mm")
		(property "Reference" "U13"
			(at -1.182531 -1.65 90)
			(layer "F.SilkS")
			(effects
				(font
					(size 0.7 0.7)
					(thickness 0.15)
				)
				(justify left bottom)
			)
		)
		(property "Value" "TPD4E05U06QDQARQ1"
			(at 0.018 2.499 90)
			(layer "F.Fab")
			(effects
				(font
					(size 0.7 0.7)
					(thickness 0.15)
				)
				(justify left bottom)
			)
		)
		(property "Footprint" "antmicro-footprints:USON-10_2.5x1mm_P0.5mm"
			(at 0 0 90)
			(layer "F.Fab")
			(hide yes)
			(effects
				(font
					(size 1.27 1.27)
					(thickness 0.15)
				)
			)
		)
		(property "Datasheet" "https://www.ti.com/lit/ds/symlink/tpd4e05u06-q1.pdf?HQS=dis-mous-null-mousermode-dsf-pf-null-wwe&ts=1663591265741&ref_url=https%253A%252F%252Fwww.mouser.com%252F"
			(at 0 0 90)
			(layer "F.Fab")
			(hide yes)
			(effects
				(font
					(size 1.27 1.27)
					(thickness 0.15)
				)
			)
		)
		(property "Author" "Antmicro"
			(at 181.367469 41.367469 0)
			(layer "F.Fab")
			(hide yes)
			(effects
				(font
					(size 1 1)
					(thickness 0.15)
				)
			)
		)
		(property "License" "Apache-2.0"
			(at 181.367469 41.367469 0)
			(layer "F.Fab")
			(hide yes)
			(effects
				(font
					(size 1 1)
					(thickness 0.15)
				)
			)
		)
		(property "MPN" "TPD4E05U06QDQARQ1"
			(at 181.367469 41.367469 0)
			(layer "F.Fab")
			(hide yes)
			(effects
				(font
					(size 1 1)
					(thickness 0.15)
				)
			)
		)
		(property "Manufacturer" "Texas Instruments"
			(at 181.367469 41.367469 0)
			(layer "F.Fab")
			(hide yes)
			(effects
				(font
					(size 1 1)
					(thickness 0.15)
				)
			)
		)
		(sheetname "USB Debug, DP")
		(sheetfile "usb.kicad_sch")
		(attr smd)
		(fp_line
			(start 0.498 -1.401)
			(end -0.5 -1.401)
			(stroke
				(width 0.15)
				(type solid)
			)
			(layer "F.SilkS")
		)
		(fp_line
			(start 0.498 1.398)
			(end -0.5 1.398)
			(stroke
				(width 0.15)
				(type solid)
			)
			(layer "F.SilkS")
		)
		(fp_circle
			(center -0.68 -1.27)
			(end -0.63 -1.27)
			(stroke
				(width 0.15)
				(type solid)
			)
			(fill solid)
			(layer "F.SilkS")
		)
		(fp_rect
			(start -0.8 -1.5)
			(end 0.8 1.499)
			(stroke
				(width 0.05)
				(type solid)
			)
			(fill none)
			(layer "F.CrtYd")
		)
		(fp_line
			(start 0.498 -1.25)
			(end -0.25 -1.25)
			(stroke
				(width 0.15)
				(type solid)
			)
			(layer "F.Fab")
		)
		(fp_line
			(start 0.498 -1.25)
			(end 0.498 1.249)
			(stroke
				(width 0.15)
				(type solid)
			)
			(layer "F.Fab")
		)
		(fp_line
			(start -0.25 -1.25)
			(end -0.5 -1)
			(stroke
				(width 0.15)
				(type solid)
			)
			(layer "F.Fab")
		)
		(fp_line
			(start -0.5 -1)
			(end -0.5 1.249)
			(stroke
				(width 0.15)
				(type solid)
			)
			(layer "F.Fab")
		)
		(fp_line
			(start -0.5 1.249)
			(end 0.498 1.249)
			(stroke
				(width 0.15)
				(type solid)
			)
			(layer "F.Fab")
		)
		(fp_text user "${REFERENCE}"
			(at -0.802 4.498 90)
			(layer "F.Fab")
			(hide yes)
			(effects
				(font
					(size 0.7 0.7)
					(thickness 0.15)
				)
				(justify left bottom)
			)
		)
		(fp_text user "Author: Antmicro"
			(at -0.802 5.7 90)
			(layer "F.Fab")
			(hide yes)
			(effects
				(font
					(size 0.7 0.7)
					(thickness 0.15)
				)
				(justify left bottom)
			)
		)
		(fp_text user "License: Apache-2.0"
			(at -0.802 6.9 90)
			(layer "F.Fab")
			(hide yes)
			(effects
				(font
					(size 0.7 0.7)
					(thickness 0.15)
				)
				(justify left bottom)
			)
		)
		(pad "1" smd roundrect
			(at -0.387 -1)
			(size 0.25 0.55)
			(layers "F.Cu" "F.Paste" "F.Mask")
			(roundrect_rratio 0.25)
			(net 614 "/USB Debug, DP/USBC0_SBU_P")
			(pintype "passive")
		)
		(pad "2" smd roundrect
			(at -0.387 -0.5)
			(size 0.25 0.55)
			(layers "F.Cu" "F.Paste" "F.Mask")
			(roundrect_rratio 0.25)
			(net 615 "/USB Debug, DP/USBC0_SBU_N")
			(pintype "passive")
		)
		(pad "3" smd roundrect
			(at -0.387 0)
			(size 0.4 0.55)
			(layers "F.Cu" "F.Paste" "F.Mask")
			(roundrect_rratio 0.25)
			(net 1 "GND")
			(pintype "power_in")
		)
		(pad "4" smd roundrect
			(at -0.387 0.498)
			(size 0.25 0.55)
			(layers "F.Cu" "F.Paste" "F.Mask")
			(roundrect_rratio 0.25)
			(net 784 "unconnected-(U13-Pad4)_1")
			(pintype "passive+no_connect")
		)
		(pad "5" smd roundrect
			(at -0.387 0.998)
			(size 0.25 0.55)
			(layers "F.Cu" "F.Paste" "F.Mask")
			(roundrect_rratio 0.25)
			(net 783 "unconnected-(U13-Pad5)_1")
			(pintype "passive+no_connect")
		)
		(pad "6" smd roundrect
			(at 0.385 0.998)
			(size 0.25 0.55)
			(layers "F.Cu" "F.Paste" "F.Mask")
			(roundrect_rratio 0.25)
			(net 558 "unconnected-(U13-Pad5)")
			(pintype "passive+no_connect")
		)
		(pad "7" smd roundrect
			(at 0.385 0.498)
			(size 0.25 0.55)
			(layers "F.Cu" "F.Paste" "F.Mask")
			(roundrect_rratio 0.25)
			(net 557 "unconnected-(U13-Pad4)")
			(pintype "passive+no_connect")
		)
		(pad "8" smd roundrect
			(at 0.385 0)
			(size 0.4 0.55)
			(layers "F.Cu" "F.Paste" "F.Mask")
			(roundrect_rratio 0.25)
			(net 1 "GND")
			(pintype "passive")
		)
		(pad "9" smd roundrect
			(at 0.385 -0.5)
			(size 0.25 0.55)
			(layers "F.Cu" "F.Paste" "F.Mask")
			(roundrect_rratio 0.25)
			(net 615 "/USB Debug, DP/USBC0_SBU_N")
			(pintype "passive")
		)
		(pad "10" smd roundrect
			(at 0.385 -1)
			(size 0.25 0.55)
			(layers "F.Cu" "F.Paste" "F.Mask")
			(roundrect_rratio 0.25)
			(net 614 "/USB Debug, DP/USBC0_SBU_P")
			(pintype "passive")
		)
	)
	(footprint "antmicro-footprints:XDFN-2_1x0.60mm"
		(layer "F.Cu")
		(at 87.3 127.05 90)
		(property "Reference" "D61"
			(at 2.25 0.25 90)
			(layer "F.SilkS")
			(effects
				(font
					(size 0.7 0.7)
					(thickness 0.15)
				)
				(justify left bottom)
			)
		)
		(property "Value" "TPD1E0B04_XDFN-2"
			(at 0 1.5 90)
			(layer "F.Fab")
			(effects
				(font
					(size 0.7 0.7)
					(thickness 0.15)
				)
				(justify left bottom)
			)
		)
		(property "Footprint" "antmicro-footprints:XDFN-2_1x0.60mm"
			(at 0 0 90)
			(layer "F.Fab")
			(hide yes)
			(effects
				(font
					(size 1.27 1.27)
					(thickness 0.15)
				)
			)
		)
		(property "Datasheet" "https://www.ti.com/general/docs/suppproductinfo.tsp?distId=26&gotoUrl=https://www.ti.com/lit/gpn/tpd1e0b04"
			(at 0 0 90)
			(layer "F.Fab")
			(hide yes)
			(effects
				(font
					(size 1.27 1.27)
					(thickness 0.15)
				)
			)
		)
		(property "MPN" "TPD1E0B04DPYR"
			(at 214.35 39.75 0)
			(layer "F.Fab")
			(hide yes)
			(effects
				(font
					(size 1 1)
					(thickness 0.15)
				)
			)
		)
		(property "Manufacturer" "Texas Instruments"
			(at 214.35 39.75 0)
			(layer "F.Fab")
			(hide yes)
			(effects
				(font
					(size 1 1)
					(thickness 0.15)
				)
			)
		)
		(property "Author" "Antmicro"
			(at 214.35 39.75 0)
			(layer "F.Fab")
			(hide yes)
			(effects
				(font
					(size 1 1)
					(thickness 0.15)
				)
			)
		)
		(property "License" "Apache-2.0"
			(at 214.35 39.75 0)
			(layer "F.Fab")
			(hide yes)
			(effects
				(font
					(size 1 1)
					(thickness 0.15)
				)
			)
		)
		(sheetname "Supply")
		(sheetfile "supply.kicad_sch")
		(attr smd)
		(fp_rect
			(start -0.725 -0.475)
			(end 0.725 0.475)
			(stroke
				(width 0.05)
				(type solid)
			)
			(fill none)
			(layer "F.CrtYd")
		)
		(fp_rect
			(start -0.55 -0.35)
			(end 0.55 0.35)
			(stroke
				(width 0.15)
				(type solid)
			)
			(fill none)
			(layer "F.Fab")
		)
		(fp_text user "Author: Antmicro"
			(at -0.8 4.4 90)
			(layer "F.Fab")
			(hide yes)
			(effects
				(font
					(size 0.7 0.7)
					(thickness 0.15)
				)
				(justify left bottom)
			)
		)
		(fp_text user "${REFERENCE}"
			(at -0.8 3.2 90)
			(layer "F.Fab")
			(hide yes)
			(effects
				(font
					(size 0.7 0.7)
					(thickness 0.15)
				)
				(justify left bottom)
			)
		)
		(fp_text user "License: Apache-2.0"
			(at -0.8 5.6 90)
			(layer "F.Fab")
			(hide yes)
			(effects
				(font
					(size 0.7 0.7)
					(thickness 0.15)
				)
				(justify left bottom)
			)
		)
		(pad "1" smd roundrect
			(at -0.351 0 90)
			(size 0.3 0.5)
			(layers "F.Cu" "F.Paste" "F.Mask")
			(roundrect_rratio 0.25)
			(net 1 "GND")
			(pinfunction "C")
			(pintype "passive")
		)
		(pad "2" smd roundrect
			(at 0.349 0 90)
			(size 0.3 0.5)
			(layers "F.Cu" "F.Paste" "F.Mask")
			(roundrect_rratio 0.25)
			(net 179 "Net-(D61-A)")
			(pinfunction "A")
			(pintype "passive")
		)
	)
	(footprint "antmicro-footprints:C_0603_1608Metric_EIA"
		(layer "F.Cu")
		(at 56.64 94.63 90)
		(descr "Capacitor SMD 0603, IPC-7351 Density Level A")
		(tags "Capacitor 0603")
		(property "Reference" "C120"
			(at -2.32 28.253333 90)
			(layer "F.SilkS")
			(effects
				(font
					(size 0.7 0.7)
					(thickness 0.15)
				)
				(justify left bottom)
			)
		)
		(property "Value" "C_22u_16V_0603"
			(at -1.42757 1.770288 90)
			(layer "F.Fab")
			(effects
				(font
					(size 0.7 0.7)
					(thickness 0.15)
				)
				(justify left bottom)
			)
		)
		(property "Footprint" "antmicro-footprints:C_0603_1608Metric_EIA"
			(at 0 0 90)
			(layer "F.Fab")
			(hide yes)
			(effects
				(font
					(size 1.27 1.27)
					(thickness 0.15)
				)
			)
		)
		(property "Datasheet" "https://product.samsungsem.com/mlcc/CL10A226MO7JZN.do"
			(at 0 0 90)
			(layer "F.Fab")
			(hide yes)
			(effects
				(font
					(size 1.27 1.27)
					(thickness 0.15)
				)
			)
		)
		(property "Description" "SMD Multilayer Ceramic Capacitor"
			(at 0 0 90)
			(layer "F.Fab")
			(hide yes)
			(effects
				(font
					(size 1.27 1.27)
					(thickness 0.15)
				)
			)
		)
		(property "Manufacturer" "Samsung Electro-Mechanics"
			(at 0 0 90)
			(unlocked yes)
			(layer "F.Fab")
			(hide yes)
			(effects
				(font
					(size 1 1)
					(thickness 0.15)
				)
			)
		)
		(property "MPN" "CL10A226MO7JZNC"
			(at 0 0 90)
			(unlocked yes)
			(layer "F.Fab")
			(hide yes)
			(effects
				(font
					(size 1 1)
					(thickness 0.15)
				)
			)
		)
		(property "Val" "22u"
			(at 0 0 90)
			(unlocked yes)
			(layer "F.Fab")
			(hide yes)
			(effects
				(font
					(size 1 1)
					(thickness 0.15)
				)
			)
		)
		(property "License" "Apache-2.0"
			(at 0 0 90)
			(unlocked yes)
			(layer "F.Fab")
			(hide yes)
			(effects
				(font
					(size 1 1)
					(thickness 0.15)
				)
			)
		)
		(property "Author" "Antmicro"
			(at 0 0 90)
			(unlocked yes)
			(layer "F.Fab")
			(hide yes)
			(effects
				(font
					(size 1 1)
					(thickness 0.15)
				)
			)
		)
		(property "Voltage" "16V"
			(at 0 0 90)
			(unlocked yes)
			(layer "F.Fab")
			(hide yes)
			(effects
				(font
					(size 1 1)
					(thickness 0.15)
				)
			)
		)
		(property "Dielectric" ""
			(at 0 0 90)
			(unlocked yes)
			(layer "F.Fab")
			(hide yes)
			(effects
				(font
					(size 1 1)
					(thickness 0.15)
				)
			)
		)
		(sheetname "Supply")
		(sheetfile "supply.kicad_sch")
		(attr smd)
		(fp_line
			(start -0.15 -0.55)
			(end 0.15 -0.55)
			(stroke
				(width 0.15)
				(type solid)
			)
			(layer "F.SilkS")
		)
		(fp_line
			(start -0.15 0.55)
			(end 0.15 0.55)
			(stroke
				(width 0.15)
				(type solid)
			)
			(layer "F.SilkS")
		)
		(fp_rect
			(start -1.25 -0.65)
			(end 1.25 0.65)
			(stroke
				(width 0.05)
				(type solid)
			)
			(fill none)
			(layer "F.CrtYd")
		)
		(fp_rect
			(start -0.8 -0.45)
			(end 0.8 0.45)
			(stroke
				(width 0.15)
				(type solid)
			)
			(fill none)
			(layer "F.Fab")
		)
		(fp_text user "${REFERENCE}"
			(at -1.682 3.895 90)
			(layer "F.Fab")
			(hide yes)
			(effects
				(font
					(size 0.7 0.7)
					(thickness 0.15)
				)
				(justify left bottom)
			)
		)
		(fp_text user "Author: Antmicro"
			(at -1.682 4.894 90)
			(layer "F.Fab")
			(hide yes)
			(effects
				(font
					(size 0.7 0.7)
					(thickness 0.15)
				)
				(justify left bottom)
			)
		)
		(fp_text user "License: Apache-2.0"
			(at -1.682 5.895 90)
			(layer "F.Fab")
			(hide yes)
			(effects
				(font
					(size 0.7 0.7)
					(thickness 0.15)
				)
				(justify left bottom)
			)
		)
		(pad "1" smd roundrect
			(at -0.7 0 90)
			(size 0.8 1.1)
			(layers "F.Cu" "F.Paste" "F.Mask")
			(roundrect_rratio 0.2)
			(net 1 "GND")
			(pintype "passive")
		)
		(pad "2" smd roundrect
			(at 0.7 0 90)
			(size 0.8 1.1)
			(layers "F.Cu" "F.Paste" "F.Mask")
			(roundrect_rratio 0.2)
			(net 761 "/Supply/5V_OUT")
			(pintype "passive")
		)
	)
	(footprint "antmicro-footprints:XDFN-2_1x0.60mm"
		(layer "F.Cu")
		(at 147.45 88.2 -90)
		(property "Reference" "D40"
			(at -6.65 0.15 180)
			(layer "F.SilkS")
			(effects
				(font
					(size 0.7 0.7)
					(thickness 0.15)
				)
				(justify left bottom)
			)
		)
		(property "Value" "TPD1E0B04_XDFN-2"
			(at 0 1.5 -90)
			(layer "F.Fab")
			(effects
				(font
					(size 0.7 0.7)
					(thickness 0.15)
				)
				(justify left bottom)
			)
		)
		(property "Footprint" "antmicro-footprints:XDFN-2_1x0.60mm"
			(at 0 0 -90)
			(layer "F.Fab")
			(hide yes)
			(effects
				(font
					(size 1.27 1.27)
					(thickness 0.15)
				)
			)
		)
		(property "Datasheet" "https://www.ti.com/general/docs/suppproductinfo.tsp?distId=26&gotoUrl=https://www.ti.com/lit/gpn/tpd1e0b04"
			(at 0 0 -90)
			(layer "F.Fab")
			(hide yes)
			(effects
				(font
					(size 1.27 1.27)
					(thickness 0.15)
				)
			)
		)
		(property "MPN" "TPD1E0B04DPYR"
			(at 59.25 235.65 0)
			(layer "F.Fab")
			(hide yes)
			(effects
				(font
					(size 1 1)
					(thickness 0.15)
				)
			)
		)
		(property "Manufacturer" "Texas Instruments"
			(at 59.25 235.65 0)
			(layer "F.Fab")
			(hide yes)
			(effects
				(font
					(size 1 1)
					(thickness 0.15)
				)
			)
		)
		(property "Author" "Antmicro"
			(at 59.25 235.65 0)
			(layer "F.Fab")
			(hide yes)
			(effects
				(font
					(size 1 1)
					(thickness 0.15)
				)
			)
		)
		(property "License" "Apache-2.0"
			(at 59.25 235.65 0)
			(layer "F.Fab")
			(hide yes)
			(effects
				(font
					(size 1 1)
					(thickness 0.15)
				)
			)
		)
		(sheetname "Peripherals")
		(sheetfile "peripherals.kicad_sch")
		(attr smd)
		(fp_rect
			(start -0.725 -0.475)
			(end 0.725 0.475)
			(stroke
				(width 0.05)
				(type solid)
			)
			(fill none)
			(layer "F.CrtYd")
		)
		(fp_rect
			(start -0.55 -0.35)
			(end 0.55 0.35)
			(stroke
				(width 0.15)
				(type solid)
			)
			(fill none)
			(layer "F.Fab")
		)
		(fp_text user "License: Apache-2.0"
			(at -0.8 5.6 -90)
			(layer "F.Fab")
			(hide yes)
			(effects
				(font
					(size 0.7 0.7)
					(thickness 0.15)
				)
				(justify left bottom)
			)
		)
		(fp_text user "Author: Antmicro"
			(at -0.8 4.4 -90)
			(layer "F.Fab")
			(hide yes)
			(effects
				(font
					(size 0.7 0.7)
					(thickness 0.15)
				)
				(justify left bottom)
			)
		)
		(fp_text user "${REFERENCE}"
			(at -0.8 3.2 -90)
			(layer "F.Fab")
			(hide yes)
			(effects
				(font
					(size 0.7 0.7)
					(thickness 0.15)
				)
				(justify left bottom)
			)
		)
		(pad "1" smd roundrect
			(at -0.351 0 270)
			(size 0.3 0.5)
			(layers "F.Cu" "F.Paste" "F.Mask")
			(roundrect_rratio 0.25)
			(net 131 "PCIE2_RX0_P")
			(pinfunction "C")
			(pintype "passive")
		)
		(pad "2" smd roundrect
			(at 0.349 0 270)
			(size 0.3 0.5)
			(layers "F.Cu" "F.Paste" "F.Mask")
			(roundrect_rratio 0.25)
			(net 1 "GND")
			(pinfunction "A")
			(pintype "passive")
		)
	)
	(footprint "antmicro-footprints:R_0402_1005Metric"
		(layer "F.Cu")
		(at 102.95 89.8 -90)
		(descr "Resistor SMD 0402")
		(tags "resistor SMD 0402")
		(property "Reference" "R47"
			(at 0.98 -1.37 -90)
			(layer "F.SilkS")
			(effects
				(font
					(size 0.7 0.7)
					(thickness 0.15)
				)
				(justify left bottom)
			)
		)
		(property "Value" "R_10k_0402"
			(at 0 1.4 -90)
			(layer "F.Fab")
			(effects
				(font
					(size 0.7 0.7)
					(thickness 0.15)
				)
				(justify left bottom)
			)
		)
		(property "Footprint" "antmicro-footprints:R_0402_1005Metric"
			(at 0 0 -90)
			(layer "F.Fab")
			(hide yes)
			(effects
				(font
					(size 1.27 1.27)
					(thickness 0.15)
				)
			)
		)
		(property "Datasheet" "https://www.bourns.com/docs/product-datasheets/cr.pdf"
			(at 0 0 -90)
			(layer "F.Fab")
			(hide yes)
			(effects
				(font
					(size 1.27 1.27)
					(thickness 0.15)
				)
			)
		)
		(property "Author" "Antmicro"
			(at 13.15 192.75 0)
			(layer "F.Fab")
			(hide yes)
			(effects
				(font
					(size 1 1)
					(thickness 0.15)
				)
			)
		)
		(property "License" "Apache-2.0"
			(at 13.15 192.75 0)
			(layer "F.Fab")
			(hide yes)
			(effects
				(font
					(size 1 1)
					(thickness 0.15)
				)
			)
		)
		(property "MPN" "CR0402-FX-1002GLF"
			(at 13.15 192.75 0)
			(layer "F.Fab")
			(hide yes)
			(effects
				(font
					(size 1 1)
					(thickness 0.15)
				)
			)
		)
		(property "Manufacturer" "Bourns"
			(at 13.15 192.75 0)
			(layer "F.Fab")
			(hide yes)
			(effects
				(font
					(size 1 1)
					(thickness 0.15)
				)
			)
		)
		(property "Tolerance" "1%"
			(at 13.15 192.75 0)
			(layer "F.Fab")
			(hide yes)
			(effects
				(font
					(size 1 1)
					(thickness 0.15)
				)
			)
		)
		(property "Val" "10k"
			(at 13.15 192.75 0)
			(layer "F.Fab")
			(hide yes)
			(effects
				(font
					(size 1 1)
					(thickness 0.15)
				)
			)
		)
		(sheetname "HDMI")
		(sheetfile "hdmi.kicad_sch")
		(attr smd)
		(fp_rect
			(start -0.925 -0.47)
			(end 0.925 0.47)
			(stroke
				(width 0.05)
				(type default)
			)
			(fill none)
			(layer "F.CrtYd")
		)
		(fp_rect
			(start -0.5 -0.25)
			(end 0.5 0.25)
			(stroke
				(width 0.15)
				(type solid)
			)
			(fill none)
			(layer "F.Fab")
		)
		(fp_text user "${REFERENCE}"
			(at -0.95 3.168 -90)
			(layer "F.Fab")
			(hide yes)
			(effects
				(font
					(size 0.7 0.7)
					(thickness 0.15)
				)
				(justify left bottom)
			)
		)
		(fp_text user "Author: Antmicro"
			(at -0.95 4.169 -90)
			(layer "F.Fab")
			(hide yes)
			(effects
				(font
					(size 0.7 0.7)
					(thickness 0.15)
				)
				(justify left bottom)
			)
		)
		(fp_text user "License: Apache-2.0"
			(at -0.95 5.169 -90)
			(layer "F.Fab")
			(hide yes)
			(effects
				(font
					(size 0.7 0.7)
					(thickness 0.15)
				)
				(justify left bottom)
			)
		)
		(pad "1" smd roundrect
			(at -0.48 0 270)
			(size 0.59 0.64)
			(layers "F.Cu" "F.Paste" "F.Mask")
			(roundrect_rratio 0.25)
			(net 621 "Net-(Q1-S)")
			(pintype "passive")
		)
		(pad "2" smd roundrect
			(at 0.48 0 270)
			(size 0.59 0.64)
			(layers "F.Cu" "F.Paste" "F.Mask")
			(roundrect_rratio 0.25)
			(net 112 "+1V8")
			(pintype "passive")
		)
	)
)
